# BASEBOARD_FAB2 (Tioga Pass) — schematic netlist excerpt (pin names and nets, part order shuffled) for the footprints in the layout excerpt that follows; sources: Cadence DE-HDL packaged netlist, KiCad conversion of Wiwynn_Tioga_Pass_MB.brd

J6T1  SCONN288_H44441003  SCONN  pkg PIP  page 44
  \12v\(1)  = P12V_NVDIMM_ABC
  VSS(93)  = GND
  DQ(4)  = M_A_DQ<4>
  VSS(92)  = GND
  DQ(0)  = M_A_DQ<0>
  VSS(91)  = GND
  DQS9P  = M_A_DQS_DP<9>
  DQS9N  = M_A_DQS_DN<9>
  VSS(90)  = GND
  DQ(6)  = M_A_DQ<6>
  VSS(89)  = GND
  DQ(2)  = M_A_DQ<2>
  VSS(88)  = GND
  DQ(12)  = M_A_DQ<12>
  VSS(87)  = GND
  DQ(8)  = M_A_DQ<8>
  VSS(86)  = GND
  DQS10P  = M_A_DQS_DP<10>
  DQS10N  = M_A_DQS_DN<10>
  VSS(85)  = GND
  DQ(14)  = M_A_DQ<14>
  VSS(84)  = GND
  DQ(10)  = M_A_DQ<10>
  VSS(83)  = GND
  DQ(20)  = M_A_DQ<20>
  VSS(82)  = GND
  DQ(16)  = M_A_DQ<16>
  VSS(81)  = GND
  DQS11P  = M_A_DQS_DP<11>
  DQS11N  = M_A_DQS_DN<11>
  VSS(80)  = GND
  DQ(22)  = M_A_DQ<22>
  VSS(79)  = GND
  DQ(18)  = M_A_DQ<18>
  VSS(78)  = GND
  DQ(28)  = M_A_DQ<28>
  VSS(77)  = GND
  DQ(24)  = M_A_DQ<24>
  VSS(76)  = GND
  DQS12P  = M_A_DQS_DP<12>
  DQS12N  = M_A_DQS_DN<12>
  VSS(75)  = GND
  DQ(30)  = M_A_DQ<30>
  VSS(74)  = GND
  DQ(26)  = M_A_DQ<26>
  VSS(73)  = GND
  CB(4)  = M_A_ECC<4>
  VSS(72)  = GND
  CB(0)  = M_A_ECC<0>
  VSS(71)  = GND
  DQS17P  = M_A_DQS_DP<17>
  DQS17N  = M_A_DQS_DN<17>
  VSS(70)  = GND
  CB(6)  = M_A_ECC<6>
  VSS(69)  = GND
  CB(2)  = M_A_ECC<2>
  VSS(68)  = GND
  RESET_N  = M_ABC_RST_N
  VDD(25)  = PVDDQ_ABC
  CKE(0)  = M_A_CKE<2>
  VDD(24)  = PVDDQ_ABC
  ACT_N  = M_A_ACT_N
  BG(0)  = M_A_BG<0>
  VDD(23)  = PVDDQ_ABC
  A12  = M_A_MA<12>
  A9  = M_A_MA<9>
  VDD(22)  = PVDDQ_ABC
  A8  = M_A_MA<8>
  A6  = M_A_MA<6>
  VDD(21)  = PVDDQ_ABC
  A3  = M_A_MA<3>
  A1  = M_A_MA<1>
  VDD(20)  = PVDDQ_ABC
  CK0P  = M_A_CLK_DP<2>
  CK0N  = M_A_CLK_DN<2>
  VDD(19)  = PVDDQ_ABC
  VTT(1)  = PVTT_ABC
  EVENT_N  = FM_DIMM_EVENT_COD_N
  A0  = M_A_MA<0>
  VDD(18)  = PVDDQ_ABC
  BA(0)  = M_A_BA<0>
  A16_RAS_N  = M_A_MA<16>
  VDD(17)  = PVDDQ_ABC
  S0_N  = M_A_CS_N<4>
  VDD(16)  = PVDDQ_ABC
  A15_CAS_N  = M_A_MA<15>
  ODT(0)  = M_A_ODT<2>
  VDD(15)  = PVDDQ_ABC
  S1_N  = M_A_CS_N<5>
  VDD(14)  = PVDDQ_ABC
  ODT(1)  = M_A_ODT<3>
  VDD(13)  = PVDDQ_ABC
  S2_N_C(0)  = M_A_CS_N<6>
  VSS(67)  = GND
  DQ(36)  = M_A_DQ<36>
  VSS(66)  = GND
  DQ(32)  = M_A_DQ<32>
  VSS(65)  = GND
  DQS13P  = M_A_DQS_DP<13>
  DQS13N  = M_A_DQS_DN<13>
  VSS(64)  = GND
  DQ(38)  = M_A_DQ<38>
  VSS(63)  = GND
  DQ(34)  = M_A_DQ<34>
  VSS(62)  = GND
  DQ(44)  = M_A_DQ<44>
  VSS(61)  = GND
  DQ(40)  = M_A_DQ<40>
  VSS(60)  = GND
  DQS14P  = M_A_DQS_DP<14>
  DQS14N  = M_A_DQS_DN<14>
  VSS(59)  = GND
  DQ(46)  = M_A_DQ<46>
  VSS(58)  = GND
  DQ(42)  = M_A_DQ<42>
  VSS(57)  = GND
  DQ(52)  = M_A_DQ<52>
  VSS(56)  = GND
  DQ(48)  = M_A_DQ<48>
  VSS(55)  = GND
  DQS15P  = M_A_DQS_DP<15>
  DQS15N  = M_A_DQS_DN<15>
  VSS(54)  = GND
  DQ(54)  = M_A_DQ<54>
  VSS(53)  = GND
  DQ(50)  = M_A_DQ<50>
  VSS(52)  = GND
  DQ(60)  = M_A_DQ<60>
  VSS(51)  = GND
  DQ(56)  = M_A_DQ<56>
  VSS(50)  = GND
  DQS16P  = M_A_DQS_DP<16>
  DQS16N  = M_A_DQS_DN<16>
  VSS(49)  = GND
  DQ(62)  = M_A_DQ<62>
  VSS(48)  = GND
  DQ(58)  = M_A_DQ<58>
  VSS(47)  = GND
  SA(0)  = PVPP_ABC
  SA(1)  = GND
  SCL  = SMB_DDR_ABC_VPP_SCL
  VPP(4)  = PVPP_ABC
  VPP(3)  = PVPP_ABC
  RFU(2)  = TP_CH_A_DIMM_A1_RFU_2
  \12v\(0)  = P12V_NVDIMM_ABC
  VREFCA  = M_A_VREF
  VSS(46)  = GND
  DQ(5)  = M_A_DQ<5>
  VSS(45)  = GND
  DQ(1)  = M_A_DQ<1>
  VSS(44)  = GND
  DQS0N  = M_A_DQS_DN<0>
  DQS0P  = M_A_DQS_DP<0>
  VSS(43)  = GND
  DQ(7)  = M_A_DQ<7>
  VSS(42)  = GND
  DQ(3)  = M_A_DQ<3>
  VSS(41)  = GND
  DQ(13)  = M_A_DQ<13>
  VSS(40)  = GND
  DQ(9)  = M_A_DQ<9>
  VSS(39)  = GND
  DQS1N  = M_A_DQS_DN<1>
  DQS1P  = M_A_DQS_DP<1>
  VSS(38)  = GND
  DQ(15)  = M_A_DQ<15>
  VSS(37)  = GND
  DQ(11)  = M_A_DQ<11>
  VSS(36)  = GND
  DQ(21)  = M_A_DQ<21>
  VSS(35)  = GND
  DQ(17)  = M_A_DQ<17>
  VSS(34)  = GND
  DQS2N  = M_A_DQS_DN<2>
  DQS2P  = M_A_DQS_DP<2>
  VSS(33)  = GND
  DQ(23)  = M_A_DQ<23>
  VSS(32)  = GND
  DQ(19)  = M_A_DQ<19>
  VSS(31)  = GND
  DQ(29)  = M_A_DQ<29>
  VSS(30)  = GND
  DQ(25)  = M_A_DQ<25>
  VSS(29)  = GND
  DQS3N  = M_A_DQS_DN<3>
  DQS3P  = M_A_DQS_DP<3>
  VSS(28)  = GND
  DQ(31)  = M_A_DQ<31>
  VSS(27)  = GND
  DQ(27)  = M_A_DQ<27>
  VSS(26)  = GND
  CB(5)  = M_A_ECC<5>
  VSS(25)  = GND
  CB(1)  = M_A_ECC<1>
  VSS(24)  = GND
  DQS8N  = M_A_DQS_DN<8>
  DQS8P  = M_A_DQS_DP<8>
  VSS(23)  = GND
  CB(7)  = M_A_ECC<7>
  VSS(22)  = GND
  CB(3)  = M_A_ECC<3>
  VSS(21)  = GND
  CKE(1)  = M_A_CKE<3>
  VDD(12)  = PVDDQ_ABC
  RFU(0)  = TP_CH_A_DIMM_A1_RFU_0
  VDD(11)  = PVDDQ_ABC
  BG(1)  = M_A_BG<1>
  ALERT_N  = M_A_ALERT_N
  VDD(10)  = PVDDQ_ABC
  A11  = M_A_MA<11>
  A7  = M_A_MA<7>
  VDD(9)  = PVDDQ_ABC
  A5  = M_A_MA<5>
  A4  = M_A_MA<4>
  VDD(8)  = PVDDQ_ABC
  A2  = M_A_MA<2>
  VDD(7)  = PVDDQ_ABC
  CK1P  = M_A_CLK_DP<3>
  CK1N  = M_A_CLK_DN<3>
  VDD(6)  = PVDDQ_ABC
  VTT(0)  = PVTT_ABC
  PAR  = M_A_PAR
  VDD(5)  = PVDDQ_ABC
  BA(1)  = M_A_BA<1>
  A10  = M_A_MA<10>
  VDD(4)  = PVDDQ_ABC
  RFU(1)  = TP_CH_A_DIMM_A1_RFU_1
  A14_WE_N  = M_A_MA<14>
  VDD(3)  = PVDDQ_ABC
  SAVE_N_NC  = FM_ADR_COMPLETE_ABC_N
  VDD(2)  = PVDDQ_ABC
  A13  = M_A_MA<13>
  VDD(1)  = PVDDQ_ABC
  A17  = M_A_MA<17>
  C(2)  = M_A_C<2>
  VDD(0)  = PVDDQ_ABC
  S3_N_C(1)  = M_A_CS_N<7>
  SA(2)  = GND
  VSS(20)  = GND
  DQ(37)  = M_A_DQ<37>
  VSS(19)  = GND
  DQ(33)  = M_A_DQ<33>
  VSS(18)  = GND
  DQS4N  = M_A_DQS_DN<4>
  DQS4P  = M_A_DQS_DP<4>
  VSS(17)  = GND
  DQ(39)  = M_A_DQ<39>
  VSS(16)  = GND
  DQ(35)  = M_A_DQ<35>
  VSS(15)  = GND
  DQ(45)  = M_A_DQ<45>
  VSS(14)  = GND
  DQ(41)  = M_A_DQ<41>
  VSS(13)  = GND
  DQS5N  = M_A_DQS_DN<5>
  DQS5P  = M_A_DQS_DP<5>
  VSS(12)  = GND
  DQ(47)  = M_A_DQ<47>
  VSS(11)  = GND
  DQ(43)  = M_A_DQ<43>
  VSS(10)  = GND
  DQ(53)  = M_A_DQ<53>
  VSS(9)  = GND
  DQ(49)  = M_A_DQ<49>
  VSS(8)  = GND
  DQS6N  = M_A_DQS_DN<6>
  DQS6P  = M_A_DQS_DP<6>
  VSS(7)  = GND
  DQ(55)  = M_A_DQ<55>
  VSS(6)  = GND
  DQ(51)  = M_A_DQ<51>
  VSS(5)  = GND
  DQ(61)  = M_A_DQ<61>
  VSS(4)  = GND
  DQ(57)  = M_A_DQ<57>
  VSS(3)  = GND
  DQS7N  = M_A_DQS_DN<7>
  DQS7P  = M_A_DQS_DP<7>
  VSS(2)  = GND
  DQ(63)  = M_A_DQ<63>
  VSS(1)  = GND
  DQ(59)  = M_A_DQ<59>
  VSS(0)  = GND
  VDDSPD  = PVPP_ABC
  SDA  = SMB_DDR_ABC_VPP_SDA
  VPP(1)  = PVPP_ABC
  VPP(0)  = PVPP_ABC
  VPP(2)  = PVPP_ABC

(kicad_pcb
	(version 20260206)
	(generator "pcbnew")
	(generator_version "10.0")
	(general
		(thickness 1.6)
		(legacy_teardrops no)
	)
	(paper "A4")
	(title_block
		(title "Wiwynn_Tioga_Pass_MB.brd")
		(comment 1 "Tioga Pass / footprint 3283 of 4770 (J6T1), pads 51-100 of 291")
	)
	(layers
		(0 "F.Cu" signal "TOP")
		(4 "In1.Cu" signal "L2GND")
		(6 "In2.Cu" signal "L3")
		(8 "In3.Cu" signal "L4GND")
		(10 "In4.Cu" signal "L5")
		(12 "In5.Cu" signal "L6GND")
		(14 "In6.Cu" signal "L7VCC")
		(16 "In7.Cu" signal "L8VCC")
		(18 "In8.Cu" signal "L9GND")
		(20 "In9.Cu" signal "L10")
		(22 "In10.Cu" signal "L11GND")
		(24 "In11.Cu" signal "L12")
		(26 "In12.Cu" signal "L13GND")
		(2 "B.Cu" signal "BOTTOM")
		(9 "F.Adhes" user "F.Adhesive")
		(11 "B.Adhes" user "B.Adhesive")
		(13 "F.Paste" user "Package Geometry/Pastemask Top")
		(15 "B.Paste" user "Package Geometry/Pastemask Bottom")
		(5 "F.SilkS" user "Ref Des/Silkscreen Top")
		(7 "B.SilkS" user "Ref Des/Silkscreen Bottom")
		(1 "F.Mask" user "Board Geometry/Soldermask Top")
		(3 "B.Mask" user "Board Geometry/Soldermask Bottom")
		(17 "Dwgs.User" user "User.Drawings")
		(19 "Cmts.User" user "User.Comments")
		(21 "Eco1.User" user "User.Eco1")
		(23 "Eco2.User" user "User.Eco2")
		(25 "Edge.Cuts" user "Board Geometry/Outline")
		(27 "Margin" user)
		(31 "F.CrtYd" user "Package Geometry/Place Bound Top")
		(29 "B.CrtYd" user "Package Geometry/Place Bound Bottom")
		(35 "F.Fab" user "Ref Des/Assembly Top")
		(33 "B.Fab" user "Ref Des/Assembly Bottom")
	)
	(footprint ""
		(layer "B.Cu")
		(at 194.700398 -24.824182 90)
		(property "Reference" "J6T1"
			(at 2.200148 39.23411 0)
			(unlocked yes)
			(layer "B.SilkS")
			(effects
				(font
					(size 0.7874 0.5842)
					(thickness 0.1524)
				)
				(justify left mirror)
			)
		)
		(property "Value" ""
			(at 0 0 90)
			(layer "B.Fab")
			(effects
				(font
					(size 1.27 1.27)
				)
				(justify mirror)
			)
		)
		(duplicate_pad_numbers_are_jumpers no)
		(pad "48" smd rect
			(at 0 39.949882 270)
			(size 1.8034 0.508)
			(layers "B.Cu" "B.Mask" "B.Paste")
			(net "GND")
		)
		(pad "49" smd rect
			(at 0 40.80002 270)
			(size 1.8034 0.508)
			(layers "B.Cu" "B.Mask" "B.Paste")
			(net "M_A_ECC<0>")
		)
		(pad "50" smd rect
			(at 0 41.649904 270)
			(size 1.8034 0.508)
			(layers "B.Cu" "B.Mask" "B.Paste")
			(net "GND")
		)
		(pad "51" smd rect
			(at 0 42.500042 270)
			(size 1.8034 0.508)
			(layers "B.Cu" "B.Mask" "B.Paste")
			(net "M_A_DQS_DP<17>")
		)
		(pad "52" smd rect
			(at 0 43.349926 270)
			(size 1.8034 0.508)
			(layers "B.Cu" "B.Mask" "B.Paste")
			(net "M_A_DQS_DN<17>")
		)
		(pad "53" smd rect
			(at 0 44.200064 270)
			(size 1.8034 0.508)
			(layers "B.Cu" "B.Mask" "B.Paste")
			(net "GND")
		)
		(pad "54" smd rect
			(at 0 45.049948 270)
			(size 1.8034 0.508)
			(layers "B.Cu" "B.Mask" "B.Paste")
			(net "M_A_ECC<6>")
		)
		(pad "55" smd rect
			(at 0 45.900086 270)
			(size 1.8034 0.508)
			(layers "B.Cu" "B.Mask" "B.Paste")
			(net "GND")
		)
		(pad "56" smd rect
			(at 0 46.74997 270)
			(size 1.8034 0.508)
			(layers "B.Cu" "B.Mask" "B.Paste")
			(net "M_A_ECC<2>")
		)
		(pad "57" smd rect
			(at 0 47.600108 270)
			(size 1.8034 0.508)
			(layers "B.Cu" "B.Mask" "B.Paste")
			(net "GND")
		)
		(pad "58" smd rect
			(at 0 48.449992 270)
			(size 1.8034 0.508)
			(layers "B.Cu" "B.Mask" "B.Paste")
			(net "M_ABC_RST_N")
		)
		(pad "59" smd rect
			(at 0 49.299876 270)
			(size 1.8034 0.508)
			(layers "B.Cu" "B.Mask" "B.Paste")
			(net "PVDDQ_ABC")
		)
		(pad "60" smd rect
			(at 0 50.150014 270)
			(size 1.8034 0.508)
			(layers "B.Cu" "B.Mask" "B.Paste")
			(net "M_A_CKE<2>")
		)
		(pad "61" smd rect
			(at 0 50.999898 270)
			(size 1.8034 0.508)
			(layers "B.Cu" "B.Mask" "B.Paste")
			(net "PVDDQ_ABC")
		)
		(pad "62" smd rect
			(at 0 51.850036 270)
			(size 1.8034 0.508)
			(layers "B.Cu" "B.Mask" "B.Paste")
			(net "M_A_ACT_N")
		)
		(pad "63" smd rect
			(at 0 52.69992 270)
			(size 1.8034 0.508)
			(layers "B.Cu" "B.Mask" "B.Paste")
			(net "M_A_BG<0>")
		)
		(pad "64" smd rect
			(at 0 53.550058 270)
			(size 1.8034 0.508)
			(layers "B.Cu" "B.Mask" "B.Paste")
			(net "PVDDQ_ABC")
		)
		(pad "65" smd rect
			(at 0 54.399942 270)
			(size 1.8034 0.508)
			(layers "B.Cu" "B.Mask" "B.Paste")
			(net "M_A_MA<12>")
		)
		(pad "66" smd rect
			(at 0 55.25008 270)
			(size 1.8034 0.508)
			(layers "B.Cu" "B.Mask" "B.Paste")
			(net "M_A_MA<9>")
		)
		(pad "67" smd rect
			(at 0 56.099964 270)
			(size 1.8034 0.508)
			(layers "B.Cu" "B.Mask" "B.Paste")
			(net "PVDDQ_ABC")
		)
		(pad "68" smd rect
			(at 0 56.950102 270)
			(size 1.8034 0.508)
			(layers "B.Cu" "B.Mask" "B.Paste")
			(net "M_A_MA<8>")
		)
		(pad "69" smd rect
			(at 0 57.799986 270)
			(size 1.8034 0.508)
			(layers "B.Cu" "B.Mask" "B.Paste")
			(net "M_A_MA<6>")
		)
		(pad "70" smd rect
			(at 0 58.650124 270)
			(size 1.8034 0.508)
			(layers "B.Cu" "B.Mask" "B.Paste")
			(net "PVDDQ_ABC")
		)
		(pad "71" smd rect
			(at 0 59.500008 270)
			(size 1.8034 0.508)
			(layers "B.Cu" "B.Mask" "B.Paste")
			(net "M_A_MA<3>")
		)
		(pad "72" smd rect
			(at 0 60.349892 270)
			(size 1.8034 0.508)
			(layers "B.Cu" "B.Mask" "B.Paste")
			(net "M_A_MA<1>")
		)
		(pad "73" smd rect
			(at 0 61.20003 270)
			(size 1.8034 0.508)
			(layers "B.Cu" "B.Mask" "B.Paste")
			(net "PVDDQ_ABC")
		)
		(pad "74" smd rect
			(at 0 62.049914 270)
			(size 1.8034 0.508)
			(layers "B.Cu" "B.Mask" "B.Paste")
			(net "M_A_CLK_DP<2>")
		)
		(pad "75" smd rect
			(at 0 62.900052 270)
			(size 1.8034 0.508)
			(layers "B.Cu" "B.Mask" "B.Paste")
			(net "M_A_CLK_DN<2>")
		)
		(pad "76" smd rect
			(at 0 63.749936 270)
			(size 1.8034 0.508)
			(layers "B.Cu" "B.Mask" "B.Paste")
			(net "PVDDQ_ABC")
		)
		(pad "77" smd rect
			(at 0 64.600074 270)
			(size 1.8034 0.508)
			(layers "B.Cu" "B.Mask" "B.Paste")
			(net "PVTT_ABC")
		)
		(pad "78" smd rect
			(at 0 70.550024 270)
			(size 1.8034 0.508)
			(layers "B.Cu" "B.Mask" "B.Paste")
			(net "FM_DIMM_EVENT_COD_N")
		)
		(pad "79" smd rect
			(at 0 71.399908 270)
			(size 1.8034 0.508)
			(layers "B.Cu" "B.Mask" "B.Paste")
			(net "M_A_MA<0>")
		)
		(pad "80" smd rect
			(at 0 72.250046 270)
			(size 1.8034 0.508)
			(layers "B.Cu" "B.Mask" "B.Paste")
			(net "PVDDQ_ABC")
		)
		(pad "81" smd rect
			(at 0 73.09993 270)
			(size 1.8034 0.508)
			(layers "B.Cu" "B.Mask" "B.Paste")
			(net "M_A_BA<0>")
		)
		(pad "82" smd rect
			(at 0 73.950068 270)
			(size 1.8034 0.508)
			(layers "B.Cu" "B.Mask" "B.Paste")
			(net "M_A_MA<16>")
		)
		(pad "83" smd rect
			(at 0 74.799952 270)
			(size 1.8034 0.508)
			(layers "B.Cu" "B.Mask" "B.Paste")
			(net "PVDDQ_ABC")
		)
		(pad "84" smd rect
			(at 0 75.65009 270)
			(size 1.8034 0.508)
			(layers "B.Cu" "B.Mask" "B.Paste")
			(net "M_A_CS_N<4>")
		)
		(pad "85" smd rect
			(at 0 76.499974 270)
			(size 1.8034 0.508)
			(layers "B.Cu" "B.Mask" "B.Paste")
			(net "PVDDQ_ABC")
		)
		(pad "86" smd rect
			(at 0 77.350112 270)
			(size 1.8034 0.508)
			(layers "B.Cu" "B.Mask" "B.Paste")
			(net "M_A_MA<15>")
		)
		(pad "87" smd rect
			(at 0 78.199996 270)
			(size 1.8034 0.508)
			(layers "B.Cu" "B.Mask" "B.Paste")
			(net "M_A_ODT<2>")
		)
		(pad "88" smd rect
			(at 0 79.04988 270)
			(size 1.8034 0.508)
			(layers "B.Cu" "B.Mask" "B.Paste")
			(net "PVDDQ_ABC")
		)
		(pad "89" smd rect
			(at 0 79.900018 270)
			(size 1.8034 0.508)
			(layers "B.Cu" "B.Mask" "B.Paste")
			(net "M_A_CS_N<5>")
		)
		(pad "90" smd rect
			(at 0 80.749902 270)
			(size 1.8034 0.508)
			(layers "B.Cu" "B.Mask" "B.Paste")
			(net "PVDDQ_ABC")
		)
		(pad "91" smd rect
			(at 0 81.60004 270)
			(size 1.8034 0.508)
			(layers "B.Cu" "B.Mask" "B.Paste")
			(net "M_A_ODT<3>")
		)
		(pad "92" smd rect
			(at 0 82.449924 270)
			(size 1.8034 0.508)
			(layers "B.Cu" "B.Mask" "B.Paste")
			(net "PVDDQ_ABC")
		)
		(pad "93" smd rect
			(at 0 83.300062 270)
			(size 1.8034 0.508)
			(layers "B.Cu" "B.Mask" "B.Paste")
			(net "M_A_CS_N<6>")
		)
		(pad "94" smd rect
			(at 0 84.149946 270)
			(size 1.8034 0.508)
			(layers "B.Cu" "B.Mask" "B.Paste")
			(net "GND")
		)
		(pad "95" smd rect
			(at 0 85.000084 270)
			(size 1.8034 0.508)
			(layers "B.Cu" "B.Mask" "B.Paste")
			(net "M_A_DQ<36>")
		)
		(pad "96" smd rect
			(at 0 85.849968 270)
			(size 1.8034 0.508)
			(layers "B.Cu" "B.Mask" "B.Paste")
			(net "GND")
		)
		(pad "97" smd rect
			(at 0 86.700106 270)
			(size 1.8034 0.508)
			(layers "B.Cu" "B.Mask" "B.Paste")
			(net "M_A_DQ<32>")
		)
	)
)
